# T6G (Grand Teton) — schematic netlist excerpt (pin names and nets, part order shuffled) for the footprints in the layout excerpt that follows; sources: Cadence DE-HDL packaged netlist, KiCad conversion of 04192023_DAF0TMB3IC0_F0TG_MB_C_brd_V02_OCP.brd

U6004  MOSFET_NCH_GDS_ESD_PROTECTED  2N7002K EMPTY  pkg SOT23_GDSXC  page 267
  D  = A_HSC_LOW_DRAIN
  G  = A_HSC_LOW_GATE
  S  = GND

R5238  Q_RES  3.9K 5% EMPTY  pkg 0402LF  page 234 : A = PD_U5201_EQ ; B = GND

(kicad_pcb
	(version 20260206)
	(generator "pcbnew")
	(generator_version "10.0")
	(general
		(thickness 1.6)
		(legacy_teardrops no)
	)
	(paper "A4")
	(title_block
		(title "04192023_DAF0TMB3IC0_F0TG_MB_C_brd_V02_OCP.brd")
		(comment 1 "Grand Teton / footprints 6663-6664 of 8354")
	)
	(layers
		(0 "F.Cu" signal "TOP")
		(4 "In1.Cu" signal "GND")
		(6 "In2.Cu" signal "IN1")
		(8 "In3.Cu" signal "GND1")
		(10 "In4.Cu" signal "IN2")
		(12 "In5.Cu" signal "GND2")
		(14 "In6.Cu" signal "IN3")
		(16 "In7.Cu" signal "GND3")
		(18 "In8.Cu" signal "VCC")
		(20 "In9.Cu" signal "VCC1")
		(22 "In10.Cu" signal "GND4")
		(24 "In11.Cu" signal "IN4")
		(26 "In12.Cu" signal "GND5")
		(28 "In13.Cu" signal "IN5")
		(30 "In14.Cu" signal "GND6")
		(32 "In15.Cu" signal "IN6")
		(34 "In16.Cu" signal "GND7")
		(2 "B.Cu" signal "BOTTOM")
		(9 "F.Adhes" user "F.Adhesive")
		(11 "B.Adhes" user "B.Adhesive")
		(13 "F.Paste" user "Package Geometry/Pastemask Top")
		(15 "B.Paste" user "Package Geometry/Pastemask Bottom")
		(5 "F.SilkS" user "Ref Des/Silkscreen Top")
		(7 "B.SilkS" user "Ref Des/Silkscreen Bottom")
		(1 "F.Mask" user "Board Geometry/Soldermask Top")
		(3 "B.Mask" user "Board Geometry/Soldermask Bottom")
		(17 "Dwgs.User" user "User.Drawings")
		(19 "Cmts.User" user "User.Comments")
		(21 "Eco1.User" user "User.Eco1")
		(23 "Eco2.User" user "User.Eco2")
		(25 "Edge.Cuts" user "Board Geometry/Outline")
		(27 "Margin" user)
		(31 "F.CrtYd" user "Package Geometry/Place Bound Top")
		(29 "B.CrtYd" user "Package Geometry/Place Bound Bottom")
		(35 "F.Fab" user "Ref Des/Assembly Top")
		(33 "B.Fab" user "Ref Des/Assembly Bottom")
	)
	(footprint ""
		(layer "B.Cu")
		(at 8.19277 -113.161826)
		(property "Reference" "R5238"
			(at 0 0 0)
			(layer "B.SilkS")
			(hide yes)
			(effects
				(font
					(size 1.27 1.27)
				)
				(justify mirror)
			)
		)
		(property "Value" ""
			(at 0 0 0)
			(layer "B.Fab")
			(effects
				(font
					(size 1.27 1.27)
				)
				(justify mirror)
			)
		)
		(duplicate_pad_numbers_are_jumpers no)
		(fp_line
			(start -0.7874 -0.4064)
			(end -0.7874 0.4064)
			(stroke
				(width 0.1524)
				(type default)
			)
			(layer "B.SilkS")
		)
		(fp_line
			(start -0.7874 0.4064)
			(end 0.7874 0.4064)
			(stroke
				(width 0.1524)
				(type default)
			)
			(layer "B.SilkS")
		)
		(fp_line
			(start 0.7874 -0.4064)
			(end -0.7874 -0.4064)
			(stroke
				(width 0.1524)
				(type default)
			)
			(layer "B.SilkS")
		)
		(fp_line
			(start 0.7874 0.4064)
			(end 0.7874 -0.4064)
			(stroke
				(width 0.1524)
				(type default)
			)
			(layer "B.SilkS")
		)
		(fp_line
			(start -0.67945 -0.3048)
			(end -0.67945 0.3048)
			(stroke
				(width 0.1)
				(type default)
			)
			(layer "B.Fab")
		)
		(fp_line
			(start -0.67945 0.3048)
			(end -0.120396 0.3048)
			(stroke
				(width 0.1)
				(type default)
			)
			(layer "B.Fab")
		)
		(fp_line
			(start -0.12065 -0.3048)
			(end -0.67945 -0.3048)
			(stroke
				(width 0.1)
				(type default)
			)
			(layer "B.Fab")
		)
		(fp_line
			(start -0.12065 -0.2794)
			(end -0.12065 -0.3048)
			(stroke
				(width 0.1)
				(type default)
			)
			(layer "B.Fab")
		)
		(fp_line
			(start -0.120396 0.2794)
			(end 0.12065 0.2794)
			(stroke
				(width 0.1)
				(type default)
			)
			(layer "B.Fab")
		)
		(fp_line
			(start -0.120396 0.3048)
			(end -0.120396 0.2794)
			(stroke
				(width 0.1)
				(type default)
			)
			(layer "B.Fab")
		)
		(fp_line
			(start 0.12065 -0.305054)
			(end 0.12065 -0.2794)
			(stroke
				(width 0.1)
				(type default)
			)
			(layer "B.Fab")
		)
		(fp_line
			(start 0.12065 -0.2794)
			(end -0.12065 -0.2794)
			(stroke
				(width 0.1)
				(type default)
			)
			(layer "B.Fab")
		)
		(fp_line
			(start 0.12065 0.2794)
			(end 0.12065 0.3048)
			(stroke
				(width 0.1)
				(type default)
			)
			(layer "B.Fab")
		)
		(fp_line
			(start 0.12065 0.3048)
			(end 0.67945 0.3048)
			(stroke
				(width 0.1)
				(type default)
			)
			(layer "B.Fab")
		)
		(fp_line
			(start 0.67945 -0.305054)
			(end 0.12065 -0.305054)
			(stroke
				(width 0.1)
				(type default)
			)
			(layer "B.Fab")
		)
		(fp_line
			(start 0.67945 0.3048)
			(end 0.67945 -0.305054)
			(stroke
				(width 0.1)
				(type default)
			)
			(layer "B.Fab")
		)
		(pad "1" smd circle
			(at 0.40005 0 180)
			(size 0 0)
			(layers "B.Cu" "B.Mask" "B.Paste")
			(net "PD_U5201_EQ")
		)
		(pad "2" smd circle
			(at -0.40005 0 180)
			(size 0 0)
			(layers "B.Cu" "B.Mask" "B.Paste")
			(net "GND")
		)
	)
	(footprint ""
		(layer "B.Cu")
		(at 175.387 -425.45 90)
		(property "Reference" "U6004"
			(at 4.09067 -0.172974 0)
			(unlocked yes)
			(layer "B.SilkS")
			(effects
				(font
					(size 0.7874 0.5842)
					(thickness 0.1524)
				)
				(justify left mirror)
			)
		)
		(property "Value" ""
			(at 0 0 90)
			(layer "B.Fab")
			(effects
				(font
					(size 1.27 1.27)
				)
				(justify mirror)
			)
		)
		(duplicate_pad_numbers_are_jumpers no)
		(fp_line
			(start 1.603248 -1.500124)
			(end -1.603248 -1.500124)
			(stroke
				(width 0.1524)
				(type default)
			)
			(layer "B.SilkS")
		)
		(fp_line
			(start -1.603248 -1.500124)
			(end -1.603248 1.500124)
			(stroke
				(width 0.1524)
				(type default)
			)
			(layer "B.SilkS")
		)
		(fp_line
			(start 1.603248 1.500124)
			(end 1.603248 -1.500124)
			(stroke
				(width 0.1524)
				(type default)
			)
			(layer "B.SilkS")
		)
		(fp_line
			(start -1.603248 1.500124)
			(end 1.603248 1.500124)
			(stroke
				(width 0.1524)
				(type default)
			)
			(layer "B.SilkS")
		)
		(fp_line
			(start 0.700024 -1.500124)
			(end 0.700024 -1.169924)
			(stroke
				(width 0.1)
				(type default)
			)
			(layer "B.Fab")
		)
		(fp_line
			(start -0.700024 -1.500124)
			(end 0.700024 -1.500124)
			(stroke
				(width 0.1)
				(type default)
			)
			(layer "B.Fab")
		)
		(fp_line
			(start 1.249934 -1.169924)
			(end 1.249934 -0.729996)
			(stroke
				(width 0.1)
				(type default)
			)
			(layer "B.Fab")
		)
		(fp_line
			(start 0.700024 -1.169924)
			(end 1.249934 -1.169924)
			(stroke
				(width 0.1)
				(type default)
			)
			(layer "B.Fab")
		)
		(fp_line
			(start 1.249934 -0.729996)
			(end 0.6985 -0.729996)
			(stroke
				(width 0.1)
				(type default)
			)
			(layer "B.Fab")
		)
		(fp_line
			(start 0.6985 -0.729996)
			(end 0.6985 0.729996)
			(stroke
				(width 0.1)
				(type default)
			)
			(layer "B.Fab")
		)
		(fp_line
			(start -0.700024 -0.219964)
			(end -0.700024 -1.500124)
			(stroke
				(width 0.1)
				(type default)
			)
			(layer "B.Fab")
		)
		(fp_line
			(start -1.249934 -0.219964)
			(end -0.700024 -0.219964)
			(stroke
				(width 0.1)
				(type default)
			)
			(layer "B.Fab")
		)
		(fp_line
			(start -0.700024 0.219964)
			(end -1.249934 0.219964)
			(stroke
				(width 0.1)
				(type default)
			)
			(layer "B.Fab")
		)
		(fp_line
			(start -1.249934 0.219964)
			(end -1.249934 -0.219964)
			(stroke
				(width 0.1)
				(type default)
			)
			(layer "B.Fab")
		)
		(fp_line
			(start 1.249934 0.729996)
			(end 1.249934 1.169924)
			(stroke
				(width 0.1)
				(type default)
			)
			(layer "B.Fab")
		)
		(fp_line
			(start 0.6985 0.729996)
			(end 1.249934 0.729996)
			(stroke
				(width 0.1)
				(type default)
			)
			(layer "B.Fab")
		)
		(fp_line
			(start 1.249934 1.169924)
			(end 0.700024 1.169924)
			(stroke
				(width 0.1)
				(type default)
			)
			(layer "B.Fab")
		)
		(fp_line
			(start 0.700024 1.169924)
			(end 0.700024 1.500124)
			(stroke
				(width 0.1)
				(type default)
			)
			(layer "B.Fab")
		)
		(fp_line
			(start 0.700024 1.500124)
			(end -0.700024 1.500124)
			(stroke
				(width 0.1)
				(type default)
			)
			(layer "B.Fab")
		)
		(fp_line
			(start -0.700024 1.500124)
			(end -0.700024 0.219964)
			(stroke
				(width 0.1)
				(type default)
			)
			(layer "B.Fab")
		)
		(fp_rect
			(start 0.700024 1.500124)
			(end -0.700024 -1.500124)
			(stroke
				(width 0)
				(type default)
			)
			(fill no)
			(layer "B.Fab")
		)
		(pad "D" smd rect
			(at -0.999998 0)
			(size 0.8128 0.9144)
			(layers "B.Cu" "B.Mask" "B.Paste")
			(net "A_HSC_LOW_DRAIN")
		)
		(pad "G" smd rect
			(at 0.999998 -0.94996)
			(size 0.8128 0.9144)
			(layers "B.Cu" "B.Mask" "B.Paste")
			(net "A_HSC_LOW_GATE")
		)
		(pad "S" smd rect
			(at 0.999998 0.94996)
			(size 0.8128 0.9144)
			(layers "B.Cu" "B.Mask" "B.Paste")
			(net "GND")
		)
	)
)
